(kicad_pcb
	(version 20260206)
	(generator "pcbnew")
	(generator_version "10.0")
	(general
		(thickness 1.6)
		(legacy_teardrops no)
	)
	(paper "A4")
	(title_block
		(title "01162023_DA0F0TEBIF0_F0T_Expander_BD_F_brd_V02_OCP.brd")
		(comment 1 "Grand Teton / footprints 1396-1403 of 9728")
	)
	(layers
		(0 "F.Cu" signal "TOP")
		(4 "In1.Cu" signal "GND")
		(6 "In2.Cu" signal "VCC")
		(8 "In3.Cu" signal "VCC1")
		(10 "In4.Cu" signal "GND1")
		(12 "In5.Cu" signal "IN1")
		(14 "In6.Cu" signal "GND2")
		(16 "In7.Cu" signal "IN2")
		(18 "In8.Cu" signal "GND3")
		(20 "In9.Cu" signal "IN3")
		(22 "In10.Cu" signal "GND4")
		(24 "In11.Cu" signal "IN4")
		(26 "In12.Cu" signal "GND5")
		(28 "In13.Cu" signal "IN5")
		(30 "In14.Cu" signal "GND6")
		(32 "In15.Cu" signal "IN6")
		(34 "In16.Cu" signal "GND7")
		(2 "B.Cu" signal "BOTTOM")
		(9 "F.Adhes" user "F.Adhesive")
		(11 "B.Adhes" user "B.Adhesive")
		(13 "F.Paste" user "Package Geometry/Pastemask Top")
		(15 "B.Paste" user "Package Geometry/Pastemask Bottom")
		(5 "F.SilkS" user "Ref Des/Silkscreen Top")
		(7 "B.SilkS" user "Ref Des/Silkscreen Bottom")
		(1 "F.Mask" user "Board Geometry/Soldermask Top")
		(3 "B.Mask" user "Board Geometry/Soldermask Bottom")
		(17 "Dwgs.User" user "User.Drawings")
		(19 "Cmts.User" user "User.Comments")
		(21 "Eco1.User" user "User.Eco1")
		(23 "Eco2.User" user "User.Eco2")
		(25 "Edge.Cuts" user "Board Geometry/Outline")
		(27 "Margin" user)
		(31 "F.CrtYd" user "Package Geometry/Place Bound Top")
		(29 "B.CrtYd" user "Package Geometry/Place Bound Bottom")
		(35 "F.Fab" user "Ref Des/Assembly Top")
		(33 "B.Fab" user "Ref Des/Assembly Bottom")
	)
	(footprint ""
		(layer "F.Cu")
		(at 397.967962 -18.437098)
		(property "Reference" "R1722"
			(at 0 0 0)
			(layer "F.SilkS")
			(hide yes)
			(effects
				(font
					(size 1.27 1.27)
				)
			)
		)
		(property "Value" ""
			(at 0 0 0)
			(layer "F.Fab")
			(effects
				(font
					(size 1.27 1.27)
				)
			)
		)
		(duplicate_pad_numbers_are_jumpers no)
		(fp_line
			(start -0.7874 -0.4064)
			(end 0.7874 -0.4064)
			(stroke
				(width 0.1524)
				(type default)
			)
			(layer "F.SilkS")
		)
		(fp_line
			(start -0.7874 0.4064)
			(end -0.7874 -0.4064)
			(stroke
				(width 0.1524)
				(type default)
			)
			(layer "F.SilkS")
		)
		(fp_line
			(start 0.7874 -0.4064)
			(end 0.7874 0.4064)
			(stroke
				(width 0.1524)
				(type default)
			)
			(layer "F.SilkS")
		)
		(fp_line
			(start 0.7874 0.4064)
			(end -0.7874 0.4064)
			(stroke
				(width 0.1524)
				(type default)
			)
			(layer "F.SilkS")
		)
		(fp_line
			(start -0.67945 -0.305054)
			(end -0.12065 -0.305054)
			(stroke
				(width 0.1)
				(type default)
			)
			(layer "F.Fab")
		)
		(fp_line
			(start -0.67945 0.3048)
			(end -0.67945 -0.305054)
			(stroke
				(width 0.1)
				(type default)
			)
			(layer "F.Fab")
		)
		(fp_line
			(start -0.12065 -0.305054)
			(end -0.12065 -0.2794)
			(stroke
				(width 0.1)
				(type default)
			)
			(layer "F.Fab")
		)
		(fp_line
			(start -0.12065 -0.2794)
			(end 0.12065 -0.2794)
			(stroke
				(width 0.1)
				(type default)
			)
			(layer "F.Fab")
		)
		(fp_line
			(start -0.12065 0.2794)
			(end -0.12065 0.3048)
			(stroke
				(width 0.1)
				(type default)
			)
			(layer "F.Fab")
		)
		(fp_line
			(start -0.12065 0.3048)
			(end -0.67945 0.3048)
			(stroke
				(width 0.1)
				(type default)
			)
			(layer "F.Fab")
		)
		(fp_line
			(start 0.120396 0.2794)
			(end -0.12065 0.2794)
			(stroke
				(width 0.1)
				(type default)
			)
			(layer "F.Fab")
		)
		(fp_line
			(start 0.120396 0.3048)
			(end 0.120396 0.2794)
			(stroke
				(width 0.1)
				(type default)
			)
			(layer "F.Fab")
		)
		(fp_line
			(start 0.12065 -0.3048)
			(end 0.67945 -0.3048)
			(stroke
				(width 0.1)
				(type default)
			)
			(layer "F.Fab")
		)
		(fp_line
			(start 0.12065 -0.2794)
			(end 0.12065 -0.3048)
			(stroke
				(width 0.1)
				(type default)
			)
			(layer "F.Fab")
		)
		(fp_line
			(start 0.67945 -0.3048)
			(end 0.67945 0.3048)
			(stroke
				(width 0.1)
				(type default)
			)
			(layer "F.Fab")
		)
		(fp_line
			(start 0.67945 0.3048)
			(end 0.120396 0.3048)
			(stroke
				(width 0.1)
				(type default)
			)
			(layer "F.Fab")
		)
		(pad "1" smd circle
			(at -0.40005 0)
			(size 0 0)
			(layers "F.Cu" "F.Mask" "F.Paste")
			(net "SMB_ISO_SSD13_R_SCL")
		)
		(pad "2" smd circle
			(at 0.40005 0)
			(size 0 0)
			(layers "F.Cu" "F.Mask" "F.Paste")
			(net "SMB_ISO_SSD13_SCL")
		)
	)
	(footprint ""
		(layer "F.Cu")
		(at 392.092434 -31.825184 180)
		(property "Reference" "C709"
			(at 0 0 180)
			(layer "F.SilkS")
			(hide yes)
			(effects
				(font
					(size 1.27 1.27)
				)
			)
		)
		(property "Value" ""
			(at 0 0 180)
			(layer "F.Fab")
			(effects
				(font
					(size 1.27 1.27)
				)
			)
		)
		(duplicate_pad_numbers_are_jumpers no)
		(fp_line
			(start 0.299974 0.150114)
			(end -0.299974 0.150114)
			(stroke
				(width 0.1)
				(type default)
			)
			(layer "F.Fab")
		)
		(fp_line
			(start 0.299974 -0.150114)
			(end 0.299974 0.150114)
			(stroke
				(width 0.1)
				(type default)
			)
			(layer "F.Fab")
		)
		(fp_line
			(start -0.299974 0.150114)
			(end -0.299974 -0.150114)
			(stroke
				(width 0.1)
				(type default)
			)
			(layer "F.Fab")
		)
		(fp_line
			(start -0.299974 -0.150114)
			(end 0.299974 -0.150114)
			(stroke
				(width 0.1)
				(type default)
			)
			(layer "F.Fab")
		)
		(pad "1" smd rect
			(at -0.2667 0 180)
			(size 0.3048 0.381)
			(layers "F.Cu" "F.Mask" "F.Paste")
			(net "P5E_PEX3_STN2_TX_DN<42>")
		)
		(pad "2" smd rect
			(at 0.2667 0 180)
			(size 0.3048 0.381)
			(layers "F.Cu" "F.Mask" "F.Paste")
			(net "P5E_PEX3_STN2_TX_C_DN<42>")
		)
	)
	(footprint ""
		(layer "F.Cu")
		(at 169.293032 -356.244906 90)
		(property "Reference" "C395"
			(at 0 0 90)
			(layer "F.SilkS")
			(hide yes)
			(effects
				(font
					(size 1.27 1.27)
				)
			)
		)
		(property "Value" ""
			(at 0 0 90)
			(layer "F.Fab")
			(effects
				(font
					(size 1.27 1.27)
				)
			)
		)
		(duplicate_pad_numbers_are_jumpers no)
		(fp_line
			(start 0.299974 -0.150114)
			(end 0.299974 0.150114)
			(stroke
				(width 0.1)
				(type default)
			)
			(layer "F.Fab")
		)
		(fp_line
			(start -0.299974 -0.150114)
			(end 0.299974 -0.150114)
			(stroke
				(width 0.1)
				(type default)
			)
			(layer "F.Fab")
		)
		(fp_line
			(start 0.299974 0.150114)
			(end -0.299974 0.150114)
			(stroke
				(width 0.1)
				(type default)
			)
			(layer "F.Fab")
		)
		(fp_line
			(start -0.299974 0.150114)
			(end -0.299974 -0.150114)
			(stroke
				(width 0.1)
				(type default)
			)
			(layer "F.Fab")
		)
		(pad "1" smd rect
			(at -0.2667 0 90)
			(size 0.3048 0.381)
			(layers "F.Cu" "F.Mask" "F.Paste")
			(net "P5E_PEX1_STN7_TX_DN<116>")
		)
		(pad "2" smd rect
			(at 0.2667 0 90)
			(size 0.3048 0.381)
			(layers "F.Cu" "F.Mask" "F.Paste")
			(net "P5E_PEX1_STN7_TX_C_DN<116>")
		)
	)
	(footprint ""
		(layer "F.Cu")
		(at 103.011224 -85.239606 180)
		(property "Reference" "R1469"
			(at 0 0 180)
			(layer "F.SilkS")
			(hide yes)
			(effects
				(font
					(size 1.27 1.27)
				)
			)
		)
		(property "Value" ""
			(at 0 0 180)
			(layer "F.Fab")
			(effects
				(font
					(size 1.27 1.27)
				)
			)
		)
		(duplicate_pad_numbers_are_jumpers no)
		(fp_line
			(start 0.7874 0.4064)
			(end -0.7874 0.4064)
			(stroke
				(width 0.1524)
				(type default)
			)
			(layer "F.SilkS")
		)
		(fp_line
			(start 0.7874 -0.4064)
			(end 0.7874 0.4064)
			(stroke
				(width 0.1524)
				(type default)
			)
			(layer "F.SilkS")
		)
		(fp_line
			(start -0.7874 0.4064)
			(end -0.7874 -0.4064)
			(stroke
				(width 0.1524)
				(type default)
			)
			(layer "F.SilkS")
		)
		(fp_line
			(start -0.7874 -0.4064)
			(end 0.7874 -0.4064)
			(stroke
				(width 0.1524)
				(type default)
			)
			(layer "F.SilkS")
		)
		(fp_line
			(start 0.67945 0.3048)
			(end 0.120396 0.3048)
			(stroke
				(width 0.1)
				(type default)
			)
			(layer "F.Fab")
		)
		(fp_line
			(start 0.67945 -0.3048)
			(end 0.67945 0.3048)
			(stroke
				(width 0.1)
				(type default)
			)
			(layer "F.Fab")
		)
		(fp_line
			(start 0.12065 -0.2794)
			(end 0.12065 -0.3048)
			(stroke
				(width 0.1)
				(type default)
			)
			(layer "F.Fab")
		)
		(fp_line
			(start 0.12065 -0.3048)
			(end 0.67945 -0.3048)
			(stroke
				(width 0.1)
				(type default)
			)
			(layer "F.Fab")
		)
		(fp_line
			(start 0.120396 0.3048)
			(end 0.120396 0.2794)
			(stroke
				(width 0.1)
				(type default)
			)
			(layer "F.Fab")
		)
		(fp_line
			(start 0.120396 0.2794)
			(end -0.12065 0.2794)
			(stroke
				(width 0.1)
				(type default)
			)
			(layer "F.Fab")
		)
		(fp_line
			(start -0.12065 0.3048)
			(end -0.67945 0.3048)
			(stroke
				(width 0.1)
				(type default)
			)
			(layer "F.Fab")
		)
		(fp_line
			(start -0.12065 0.2794)
			(end -0.12065 0.3048)
			(stroke
				(width 0.1)
				(type default)
			)
			(layer "F.Fab")
		)
		(fp_line
			(start -0.12065 -0.2794)
			(end 0.12065 -0.2794)
			(stroke
				(width 0.1)
				(type default)
			)
			(layer "F.Fab")
		)
		(fp_line
			(start -0.12065 -0.305054)
			(end -0.12065 -0.2794)
			(stroke
				(width 0.1)
				(type default)
			)
			(layer "F.Fab")
		)
		(fp_line
			(start -0.67945 0.3048)
			(end -0.67945 -0.305054)
			(stroke
				(width 0.1)
				(type default)
			)
			(layer "F.Fab")
		)
		(fp_line
			(start -0.67945 -0.305054)
			(end -0.12065 -0.305054)
			(stroke
				(width 0.1)
				(type default)
			)
			(layer "F.Fab")
		)
		(pad "1" smd circle
			(at -0.40005 0 180)
			(size 0 0)
			(layers "F.Cu" "F.Mask" "F.Paste")
			(net "SMB_BMC_9ZXL0851_0_7_SDA")
		)
		(pad "2" smd circle
			(at 0.40005 0 180)
			(size 0 0)
			(layers "F.Cu" "F.Mask" "F.Paste")
			(net "SMB_CLK_ISO_R_SDA")
		)
	)
	(footprint ""
		(layer "F.Cu")
		(at 80.019398 -130.794506 180)
		(property "Reference" "C23"
			(at 0 0 180)
			(layer "F.SilkS")
			(hide yes)
			(effects
				(font
					(size 1.27 1.27)
				)
			)
		)
		(property "Value" ""
			(at 0 0 180)
			(layer "F.Fab")
			(effects
				(font
					(size 1.27 1.27)
				)
			)
		)
		(duplicate_pad_numbers_are_jumpers no)
		(fp_line
			(start 0.299974 0.150114)
			(end -0.299974 0.150114)
			(stroke
				(width 0.1)
				(type default)
			)
			(layer "F.Fab")
		)
		(fp_line
			(start 0.299974 -0.150114)
			(end 0.299974 0.150114)
			(stroke
				(width 0.1)
				(type default)
			)
			(layer "F.Fab")
		)
		(fp_line
			(start -0.299974 0.150114)
			(end -0.299974 -0.150114)
			(stroke
				(width 0.1)
				(type default)
			)
			(layer "F.Fab")
		)
		(fp_line
			(start -0.299974 -0.150114)
			(end 0.299974 -0.150114)
			(stroke
				(width 0.1)
				(type default)
			)
			(layer "F.Fab")
		)
		(pad "1" smd rect
			(at -0.2667 0 180)
			(size 0.3048 0.381)
			(layers "F.Cu" "F.Mask" "F.Paste")
			(net "P5E_PEX0_STN0_TX_DP<4>")
		)
		(pad "2" smd rect
			(at 0.2667 0 180)
			(size 0.3048 0.381)
			(layers "F.Cu" "F.Mask" "F.Paste")
			(net "P5E_PEX0_STN0_TX_C_DP<4>")
		)
	)
	(footprint ""
		(layer "F.Cu")
		(at 372.782084 -38.041072 180)
		(property "Reference" "R6109"
			(at 0 0 180)
			(layer "F.SilkS")
			(hide yes)
			(effects
				(font
					(size 1.27 1.27)
				)
			)
		)
		(property "Value" ""
			(at 0 0 180)
			(layer "F.Fab")
			(effects
				(font
					(size 1.27 1.27)
				)
			)
		)
		(duplicate_pad_numbers_are_jumpers no)
		(fp_line
			(start 0.7874 0.4064)
			(end -0.7874 0.4064)
			(stroke
				(width 0.1524)
				(type default)
			)
			(layer "F.SilkS")
		)
		(fp_line
			(start 0.7874 -0.4064)
			(end 0.7874 0.4064)
			(stroke
				(width 0.1524)
				(type default)
			)
			(layer "F.SilkS")
		)
		(fp_line
			(start -0.7874 0.4064)
			(end -0.7874 -0.4064)
			(stroke
				(width 0.1524)
				(type default)
			)
			(layer "F.SilkS")
		)
		(fp_line
			(start -0.7874 -0.4064)
			(end 0.7874 -0.4064)
			(stroke
				(width 0.1524)
				(type default)
			)
			(layer "F.SilkS")
		)
		(fp_line
			(start 0.67945 0.3048)
			(end 0.120396 0.3048)
			(stroke
				(width 0.1)
				(type default)
			)
			(layer "F.Fab")
		)
		(fp_line
			(start 0.67945 -0.3048)
			(end 0.67945 0.3048)
			(stroke
				(width 0.1)
				(type default)
			)
			(layer "F.Fab")
		)
		(fp_line
			(start 0.12065 -0.2794)
			(end 0.12065 -0.3048)
			(stroke
				(width 0.1)
				(type default)
			)
			(layer "F.Fab")
		)
		(fp_line
			(start 0.12065 -0.3048)
			(end 0.67945 -0.3048)
			(stroke
				(width 0.1)
				(type default)
			)
			(layer "F.Fab")
		)
		(fp_line
			(start 0.120396 0.3048)
			(end 0.120396 0.2794)
			(stroke
				(width 0.1)
				(type default)
			)
			(layer "F.Fab")
		)
		(fp_line
			(start 0.120396 0.2794)
			(end -0.12065 0.2794)
			(stroke
				(width 0.1)
				(type default)
			)
			(layer "F.Fab")
		)
		(fp_line
			(start -0.12065 0.3048)
			(end -0.67945 0.3048)
			(stroke
				(width 0.1)
				(type default)
			)
			(layer "F.Fab")
		)
		(fp_line
			(start -0.12065 0.2794)
			(end -0.12065 0.3048)
			(stroke
				(width 0.1)
				(type default)
			)
			(layer "F.Fab")
		)
		(fp_line
			(start -0.12065 -0.2794)
			(end 0.12065 -0.2794)
			(stroke
				(width 0.1)
				(type default)
			)
			(layer "F.Fab")
		)
		(fp_line
			(start -0.12065 -0.305054)
			(end -0.12065 -0.2794)
			(stroke
				(width 0.1)
				(type default)
			)
			(layer "F.Fab")
		)
		(fp_line
			(start -0.67945 0.3048)
			(end -0.67945 -0.305054)
			(stroke
				(width 0.1)
				(type default)
			)
			(layer "F.Fab")
		)
		(fp_line
			(start -0.67945 -0.305054)
			(end -0.12065 -0.305054)
			(stroke
				(width 0.1)
				(type default)
			)
			(layer "F.Fab")
		)
		(pad "1" smd circle
			(at -0.40005 0 180)
			(size 0 0)
			(layers "F.Cu" "F.Mask" "F.Paste")
			(net "P5V_AUX")
		)
		(pad "2" smd circle
			(at 0.40005 0 180)
			(size 0 0)
			(layers "F.Cu" "F.Mask" "F.Paste")
			(net "P3V3_SSD13_PG_G2")
		)
	)
	(footprint ""
		(layer "F.Cu")
		(at 444.09233 -28.225242 180)
		(property "Reference" "C729"
			(at 0 0 180)
			(layer "F.SilkS")
			(hide yes)
			(effects
				(font
					(size 1.27 1.27)
				)
			)
		)
		(property "Value" ""
			(at 0 0 180)
			(layer "F.Fab")
			(effects
				(font
					(size 1.27 1.27)
				)
			)
		)
		(duplicate_pad_numbers_are_jumpers no)
		(fp_line
			(start 0.299974 0.150114)
			(end -0.299974 0.150114)
			(stroke
				(width 0.1)
				(type default)
			)
			(layer "F.Fab")
		)
		(fp_line
			(start 0.299974 -0.150114)
			(end 0.299974 0.150114)
			(stroke
				(width 0.1)
				(type default)
			)
			(layer "F.Fab")
		)
		(fp_line
			(start -0.299974 0.150114)
			(end -0.299974 -0.150114)
			(stroke
				(width 0.1)
				(type default)
			)
			(layer "F.Fab")
		)
		(fp_line
			(start -0.299974 -0.150114)
			(end 0.299974 -0.150114)
			(stroke
				(width 0.1)
				(type default)
			)
			(layer "F.Fab")
		)
		(pad "1" smd rect
			(at -0.2667 0 180)
			(size 0.3048 0.381)
			(layers "F.Cu" "F.Mask" "F.Paste")
			(net "P5E_PEX3_STN2_TX_DN<32>")
		)
		(pad "2" smd rect
			(at 0.2667 0 180)
			(size 0.3048 0.381)
			(layers "F.Cu" "F.Mask" "F.Paste")
			(net "P5E_PEX3_STN2_TX_C_DN<32>")
		)
	)
	(footprint ""
		(layer "F.Cu")
		(at 257.176016 -344.916252)
		(property "Reference" "R6824"
			(at 0 0 0)
			(layer "F.SilkS")
			(hide yes)
			(effects
				(font
					(size 1.27 1.27)
				)
			)
		)
		(property "Value" ""
			(at 0 0 0)
			(layer "F.Fab")
			(effects
				(font
					(size 1.27 1.27)
				)
			)
		)
		(duplicate_pad_numbers_are_jumpers no)
		(fp_line
			(start -0.7874 -0.4064)
			(end 0.7874 -0.4064)
			(stroke
				(width 0.1524)
				(type default)
			)
			(layer "F.SilkS")
		)
		(fp_line
			(start -0.7874 0.4064)
			(end -0.7874 -0.4064)
			(stroke
				(width 0.1524)
				(type default)
			)
			(layer "F.SilkS")
		)
		(fp_line
			(start 0.7874 -0.4064)
			(end 0.7874 0.4064)
			(stroke
				(width 0.1524)
				(type default)
			)
			(layer "F.SilkS")
		)
		(fp_line
			(start 0.7874 0.4064)
			(end -0.7874 0.4064)
			(stroke
				(width 0.1524)
				(type default)
			)
			(layer "F.SilkS")
		)
		(fp_line
			(start -0.67945 -0.305054)
			(end -0.12065 -0.305054)
			(stroke
				(width 0.1)
				(type default)
			)
			(layer "F.Fab")
		)
		(fp_line
			(start -0.67945 0.3048)
			(end -0.67945 -0.305054)
			(stroke
				(width 0.1)
				(type default)
			)
			(layer "F.Fab")
		)
		(fp_line
			(start -0.12065 -0.305054)
			(end -0.12065 -0.2794)
			(stroke
				(width 0.1)
				(type default)
			)
			(layer "F.Fab")
		)
		(fp_line
			(start -0.12065 -0.2794)
			(end 0.12065 -0.2794)
			(stroke
				(width 0.1)
				(type default)
			)
			(layer "F.Fab")
		)
		(fp_line
			(start -0.12065 0.2794)
			(end -0.12065 0.3048)
			(stroke
				(width 0.1)
				(type default)
			)
			(layer "F.Fab")
		)
		(fp_line
			(start -0.12065 0.3048)
			(end -0.67945 0.3048)
			(stroke
				(width 0.1)
				(type default)
			)
			(layer "F.Fab")
		)
		(fp_line
			(start 0.120396 0.2794)
			(end -0.12065 0.2794)
			(stroke
				(width 0.1)
				(type default)
			)
			(layer "F.Fab")
		)
		(fp_line
			(start 0.120396 0.3048)
			(end 0.120396 0.2794)
			(stroke
				(width 0.1)
				(type default)
			)
			(layer "F.Fab")
		)
		(fp_line
			(start 0.12065 -0.3048)
			(end 0.67945 -0.3048)
			(stroke
				(width 0.1)
				(type default)
			)
			(layer "F.Fab")
		)
		(fp_line
			(start 0.12065 -0.2794)
			(end 0.12065 -0.3048)
			(stroke
				(width 0.1)
				(type default)
			)
			(layer "F.Fab")
		)
		(fp_line
			(start 0.67945 -0.3048)
			(end 0.67945 0.3048)
			(stroke
				(width 0.1)
				(type default)
			)
			(layer "F.Fab")
		)
		(fp_line
			(start 0.67945 0.3048)
			(end 0.120396 0.3048)
			(stroke
				(width 0.1)
				(type default)
			)
			(layer "F.Fab")
		)
		(pad "1" smd circle
			(at -0.40005 0)
			(size 0 0)
			(layers "F.Cu" "F.Mask" "F.Paste")
			(net "P3V3_AUX")
		)
		(pad "2" smd circle
			(at 0.40005 0)
			(size 0 0)
			(layers "F.Cu" "F.Mask" "F.Paste")
			(net "HSC_OC_LT6700_VS")
		)
	)
)
